FILE_TYPE=LIBRARY_PARTS;
primitive '74HC1G126GW';
  pin
    '2':
      PIN_NUMBER='(2)';
      INPUT_LOAD='(-0.01,0.01)';
    '4':
      PIN_NUMBER='(4)';
      OUTPUT_TYPE='(TS,TS)';
      INPUT_LOAD='(-0.01,0.01)';
      OUTPUT_LOAD='(1.0,-1.0)';
    '5':
      PIN_NUMBER='(5)';
      PINUSE='POWER';
      NO_LOAD_CHECK='Both';
      NO_IO_CHECK='Both';
      NO_ASSERT_CHECK='TRUE';
      NO_DIR_CHECK='TRUE';
      ALLOW_CONNECT='TRUE';
    '1':
      PIN_NUMBER='(1)';
      INPUT_LOAD='(-0.01,0.01)';
    'GND':
      PIN_NUMBER='(3)';
      PINUSE='POWER';
      NO_LOAD_CHECK='Both';
      NO_IO_CHECK='Both';
      NO_ASSERT_CHECK='TRUE';
      NO_DIR_CHECK='TRUE';
      ALLOW_CONNECT='TRUE';
  end_pin;
  body
    PART_NAME='74HC1G126GW';
    BODY_NAME='74HC1G126GW';
    PHYS_DES_PREFIX='U';
    CLASS='IC';
  end_body;
end_primitive;

END.
